# T6G (Grand Teton) — schematic netlist excerpt (pin names and nets, part order shuffled) for the footprints in the layout excerpt that follows; sources: Cadence DE-HDL packaged netlist, KiCad conversion of 04192023_DAF0TMB3IC0_F0TG_MB_C_brd_V02_OCP.brd

PU204  RS31312R  IC  pkg QFN22_TH_3X5  page 135
  EN  = P12V_OCP_EN_1_R2
  LOADEN  = GND
  ENTM  = GND
  TIMER  = P12V_OCP_TIMER_1
  ISET  = P12V_OCP_ISET_1
  SS  = P12V_OCP_SS_1
  GND  = GND
  IMON  = P12V_OCP_IMON_1
  FLTB  = P12V_OCP_FLTB_1
  PG  = HP_LVC3_OCP_V3_1_P12V_PWRGD
  OV  = P12V_OCP_OV_FB_1
  AVIN  = P12V_OCP_AVIN_PD_1
  VOUT_13  = P12V_OCP_SFF
  VOUT_14  = P12V_OCP_SFF
  VOUT_15  = P12V_OCP_SFF
  VOUT_16  = P12V_OCP_SFF
  VOUT_17  = P12V_OCP_SFF
  VOUT_18  = P12V_OCP_SFF
  VOUT_19  = P12V_OCP_SFF
  VOUT_20  = P12V_OCP_SFF
  VIN_21_22  = P12V_AUX
  VIN_23  = P12V_AUX
  VIN_24  = P12V_AUX
  VIN_25  = P12V_AUX
  VIN_26  = P12V_AUX

(kicad_pcb
	(version 20260206)
	(generator "pcbnew")
	(generator_version "10.0")
	(general
		(thickness 1.6)
		(legacy_teardrops no)
	)
	(paper "A4")
	(title_block
		(title "04192023_DAF0TMB3IC0_F0TG_MB_C_brd_V02_OCP.brd")
		(comment 1 "Grand Teton / footprint 989 of 8354 (PU204), pads 1-25 of 25")
	)
	(layers
		(0 "F.Cu" signal "TOP")
		(4 "In1.Cu" signal "GND")
		(6 "In2.Cu" signal "IN1")
		(8 "In3.Cu" signal "GND1")
		(10 "In4.Cu" signal "IN2")
		(12 "In5.Cu" signal "GND2")
		(14 "In6.Cu" signal "IN3")
		(16 "In7.Cu" signal "GND3")
		(18 "In8.Cu" signal "VCC")
		(20 "In9.Cu" signal "VCC1")
		(22 "In10.Cu" signal "GND4")
		(24 "In11.Cu" signal "IN4")
		(26 "In12.Cu" signal "GND5")
		(28 "In13.Cu" signal "IN5")
		(30 "In14.Cu" signal "GND6")
		(32 "In15.Cu" signal "IN6")
		(34 "In16.Cu" signal "GND7")
		(2 "B.Cu" signal "BOTTOM")
		(9 "F.Adhes" user "F.Adhesive")
		(11 "B.Adhes" user "B.Adhesive")
		(13 "F.Paste" user "Package Geometry/Pastemask Top")
		(15 "B.Paste" user "Package Geometry/Pastemask Bottom")
		(5 "F.SilkS" user "Ref Des/Silkscreen Top")
		(7 "B.SilkS" user "Ref Des/Silkscreen Bottom")
		(1 "F.Mask" user "Board Geometry/Soldermask Top")
		(3 "B.Mask" user "Board Geometry/Soldermask Bottom")
		(17 "Dwgs.User" user "User.Drawings")
		(19 "Cmts.User" user "User.Comments")
		(21 "Eco1.User" user "User.Eco1")
		(23 "Eco2.User" user "User.Eco2")
		(25 "Edge.Cuts" user "Board Geometry/Outline")
		(27 "Margin" user)
		(31 "F.CrtYd" user "Package Geometry/Place Bound Top")
		(29 "B.CrtYd" user "Package Geometry/Place Bound Bottom")
		(35 "F.Fab" user "Ref Des/Assembly Top")
		(33 "B.Fab" user "Ref Des/Assembly Bottom")
	)
	(footprint ""
		(layer "F.Cu")
		(at 442.353192 -28.175458 -90)
		(property "Reference" "PU204"
			(at -6.397498 0.707136 0)
			(unlocked yes)
			(layer "F.SilkS")
			(effects
				(font
					(size 0.7874 0.5842)
					(thickness 0.1524)
				)
				(justify left)
			)
		)
		(property "Value" ""
			(at 0 0 270)
			(layer "F.Fab")
			(effects
				(font
					(size 1.27 1.27)
				)
			)
		)
		(duplicate_pad_numbers_are_jumpers no)
		(pad "1" smd circle
			(at -1.374902 -1.999996 180)
			(size 0 0)
			(layers "F.Cu" "F.Mask" "F.Paste")
			(net "P12V_OCP_EN_1_R2")
		)
		(pad "2" smd rect
			(at -1.400048 -1.500124 180)
			(size 0.254 0.8128)
			(layers "F.Cu" "F.Mask" "F.Paste")
			(net "GND")
		)
		(pad "3" smd rect
			(at -1.400048 -0.999998 180)
			(size 0.254 0.8128)
			(layers "F.Cu" "F.Mask" "F.Paste")
			(net "GND")
		)
		(pad "4" smd rect
			(at -1.400048 -0.499872 180)
			(size 0.254 0.8128)
			(layers "F.Cu" "F.Mask" "F.Paste")
			(net "P12V_OCP_TIMER_1")
		)
		(pad "5" smd rect
			(at -1.400048 0 180)
			(size 0.254 0.8128)
			(layers "F.Cu" "F.Mask" "F.Paste")
			(net "P12V_OCP_ISET_1")
		)
		(pad "6" smd rect
			(at -1.400048 0.499872 180)
			(size 0.254 0.8128)
			(layers "F.Cu" "F.Mask" "F.Paste")
			(net "P12V_OCP_SS_1")
		)
		(pad "7" smd rect
			(at -1.400048 0.999998 180)
			(size 0.254 0.8128)
			(layers "F.Cu" "F.Mask" "F.Paste")
			(net "GND")
		)
		(pad "8" smd rect
			(at -1.400048 1.500124 180)
			(size 0.254 0.8128)
			(layers "F.Cu" "F.Mask" "F.Paste")
			(net "P12V_OCP_IMON_1")
		)
		(pad "9" smd rect
			(at -1.400048 1.999996 180)
			(size 0.254 0.8128)
			(layers "F.Cu" "F.Mask" "F.Paste")
			(net "P12V_OCP_FLTB_1")
		)
		(pad "10" smd rect
			(at -0.499872 2.400046 270)
			(size 0.254 0.8128)
			(layers "F.Cu" "F.Mask" "F.Paste")
			(net "HP_LVC3_OCP_V3_1_P12V_PWRGD")
		)
		(pad "11" smd rect
			(at 0.499872 2.400046 270)
			(size 0.254 0.8128)
			(layers "F.Cu" "F.Mask" "F.Paste")
			(net "P12V_OCP_OV_FB_1")
		)
		(pad "12" smd rect
			(at 1.400048 1.999996 180)
			(size 0.254 0.8128)
			(layers "F.Cu" "F.Mask" "F.Paste")
			(net "P12V_OCP_AVIN_PD_1")
		)
		(pad "13" smd rect
			(at 1.400048 1.500124 180)
			(size 0.254 0.8128)
			(layers "F.Cu" "F.Mask" "F.Paste")
			(net "P12V_OCP_SFF")
		)
		(pad "14" smd rect
			(at 1.400048 0.999998 180)
			(size 0.254 0.8128)
			(layers "F.Cu" "F.Mask" "F.Paste")
			(net "P12V_OCP_SFF")
		)
		(pad "15" smd rect
			(at 1.400048 0.499872 180)
			(size 0.254 0.8128)
			(layers "F.Cu" "F.Mask" "F.Paste")
			(net "P12V_OCP_SFF")
		)
		(pad "16" smd rect
			(at 1.400048 0 180)
			(size 0.254 0.8128)
			(layers "F.Cu" "F.Mask" "F.Paste")
			(net "P12V_OCP_SFF")
		)
		(pad "17" smd rect
			(at 1.400048 -0.499872 180)
			(size 0.254 0.8128)
			(layers "F.Cu" "F.Mask" "F.Paste")
			(net "P12V_OCP_SFF")
		)
		(pad "18" smd rect
			(at 1.400048 -0.999998 180)
			(size 0.254 0.8128)
			(layers "F.Cu" "F.Mask" "F.Paste")
			(net "P12V_OCP_SFF")
		)
		(pad "19" smd rect
			(at 1.400048 -1.500124 180)
			(size 0.254 0.8128)
			(layers "F.Cu" "F.Mask" "F.Paste")
			(net "P12V_OCP_SFF")
		)
		(pad "20" smd rect
			(at 1.400048 -1.999996 180)
			(size 0.254 0.8128)
			(layers "F.Cu" "F.Mask" "F.Paste")
			(net "P12V_OCP_SFF")
		)
		(pad "21_22" smd circle
			(at 0.499872 -2.337562 180)
			(size 0 0)
			(layers "F.Cu" "F.Mask" "F.Paste")
			(net "P12V_AUX")
		)
		(pad "23" smd rect
			(at 0 -1.100074 180)
			(size 0.254 1.27)
			(layers "F.Cu" "F.Mask" "F.Paste")
			(net "P12V_AUX")
		)
		(pad "24" smd rect
			(at 0 -0.199898 180)
			(size 0.254 1.27)
			(layers "F.Cu" "F.Mask" "F.Paste")
			(net "P12V_AUX")
		)
		(pad "25" smd rect
			(at 0 0.700024 180)
			(size 0.254 1.27)
			(layers "F.Cu" "F.Mask" "F.Paste")
			(net "P12V_AUX")
		)
		(pad "26" smd rect
			(at 0 1.599946 180)
			(size 0.254 1.27)
			(layers "F.Cu" "F.Mask" "F.Paste")
			(net "P12V_AUX")
		)
	)
)
